# T6G (Grand Teton) — schematic netlist excerpt (pin names and nets, part order shuffled) for the footprints in the layout excerpt that follows; sources: Cadence DE-HDL packaged netlist, KiCad conversion of 04192023_DAF0TMB3IC0_F0TG_MB_C_brd_V02_OCP.brd

R1232  Q_RES  5.11K 1% CHIP  pkg 0402LF  page 258 : A = P1V2_AUX ; B = P1V2_AUX_ADC
R3240  Q_RES  2.2K 5% EMPTY  pkg 0402LF  page 151 : A = SMB_OCP_SFF_3V3AUX_SCL ; B = P3V3_AUX
C166  Q_CAP  10UF 25V 10% X6S  pkg C0805  page 95 : A = P12V_MEM_CPU0 ; B = GND

(kicad_pcb
	(version 20260206)
	(generator "pcbnew")
	(generator_version "10.0")
	(general
		(thickness 1.6)
		(legacy_teardrops no)
	)
	(paper "A4")
	(title_block
		(title "04192023_DAF0TMB3IC0_F0TG_MB_C_brd_V02_OCP.brd")
		(comment 1 "Grand Teton / footprints 7502-7504 of 8354")
	)
	(layers
		(0 "F.Cu" signal "TOP")
		(4 "In1.Cu" signal "GND")
		(6 "In2.Cu" signal "IN1")
		(8 "In3.Cu" signal "GND1")
		(10 "In4.Cu" signal "IN2")
		(12 "In5.Cu" signal "GND2")
		(14 "In6.Cu" signal "IN3")
		(16 "In7.Cu" signal "GND3")
		(18 "In8.Cu" signal "VCC")
		(20 "In9.Cu" signal "VCC1")
		(22 "In10.Cu" signal "GND4")
		(24 "In11.Cu" signal "IN4")
		(26 "In12.Cu" signal "GND5")
		(28 "In13.Cu" signal "IN5")
		(30 "In14.Cu" signal "GND6")
		(32 "In15.Cu" signal "IN6")
		(34 "In16.Cu" signal "GND7")
		(2 "B.Cu" signal "BOTTOM")
		(9 "F.Adhes" user "F.Adhesive")
		(11 "B.Adhes" user "B.Adhesive")
		(13 "F.Paste" user "Package Geometry/Pastemask Top")
		(15 "B.Paste" user "Package Geometry/Pastemask Bottom")
		(5 "F.SilkS" user "Ref Des/Silkscreen Top")
		(7 "B.SilkS" user "Ref Des/Silkscreen Bottom")
		(1 "F.Mask" user "Board Geometry/Soldermask Top")
		(3 "B.Mask" user "Board Geometry/Soldermask Bottom")
		(17 "Dwgs.User" user "User.Drawings")
		(19 "Cmts.User" user "User.Comments")
		(21 "Eco1.User" user "User.Eco1")
		(23 "Eco2.User" user "User.Eco2")
		(25 "Edge.Cuts" user "Board Geometry/Outline")
		(27 "Margin" user)
		(31 "F.CrtYd" user "Package Geometry/Place Bound Top")
		(29 "B.CrtYd" user "Package Geometry/Place Bound Bottom")
		(35 "F.Fab" user "Ref Des/Assembly Top")
		(33 "B.Fab" user "Ref Des/Assembly Bottom")
	)
	(footprint ""
		(layer "B.Cu")
		(at 237.923578 -323.585332)
		(property "Reference" "R1232"
			(at 0 0 0)
			(layer "B.SilkS")
			(hide yes)
			(effects
				(font
					(size 1.27 1.27)
				)
				(justify mirror)
			)
		)
		(property "Value" ""
			(at 0 0 0)
			(layer "B.Fab")
			(effects
				(font
					(size 1.27 1.27)
				)
				(justify mirror)
			)
		)
		(duplicate_pad_numbers_are_jumpers no)
		(fp_line
			(start -0.7874 -0.4064)
			(end -0.7874 0.4064)
			(stroke
				(width 0.1524)
				(type default)
			)
			(layer "B.SilkS")
		)
		(fp_line
			(start -0.7874 0.4064)
			(end 0.7874 0.4064)
			(stroke
				(width 0.1524)
				(type default)
			)
			(layer "B.SilkS")
		)
		(fp_line
			(start 0.7874 -0.4064)
			(end -0.7874 -0.4064)
			(stroke
				(width 0.1524)
				(type default)
			)
			(layer "B.SilkS")
		)
		(fp_line
			(start 0.7874 0.4064)
			(end 0.7874 -0.4064)
			(stroke
				(width 0.1524)
				(type default)
			)
			(layer "B.SilkS")
		)
		(fp_line
			(start -0.67945 -0.3048)
			(end -0.67945 0.3048)
			(stroke
				(width 0.1)
				(type default)
			)
			(layer "B.Fab")
		)
		(fp_line
			(start -0.67945 0.3048)
			(end -0.120396 0.3048)
			(stroke
				(width 0.1)
				(type default)
			)
			(layer "B.Fab")
		)
		(fp_line
			(start -0.12065 -0.3048)
			(end -0.67945 -0.3048)
			(stroke
				(width 0.1)
				(type default)
			)
			(layer "B.Fab")
		)
		(fp_line
			(start -0.12065 -0.2794)
			(end -0.12065 -0.3048)
			(stroke
				(width 0.1)
				(type default)
			)
			(layer "B.Fab")
		)
		(fp_line
			(start -0.120396 0.2794)
			(end 0.12065 0.2794)
			(stroke
				(width 0.1)
				(type default)
			)
			(layer "B.Fab")
		)
		(fp_line
			(start -0.120396 0.3048)
			(end -0.120396 0.2794)
			(stroke
				(width 0.1)
				(type default)
			)
			(layer "B.Fab")
		)
		(fp_line
			(start 0.12065 -0.305054)
			(end 0.12065 -0.2794)
			(stroke
				(width 0.1)
				(type default)
			)
			(layer "B.Fab")
		)
		(fp_line
			(start 0.12065 -0.2794)
			(end -0.12065 -0.2794)
			(stroke
				(width 0.1)
				(type default)
			)
			(layer "B.Fab")
		)
		(fp_line
			(start 0.12065 0.2794)
			(end 0.12065 0.3048)
			(stroke
				(width 0.1)
				(type default)
			)
			(layer "B.Fab")
		)
		(fp_line
			(start 0.12065 0.3048)
			(end 0.67945 0.3048)
			(stroke
				(width 0.1)
				(type default)
			)
			(layer "B.Fab")
		)
		(fp_line
			(start 0.67945 -0.305054)
			(end 0.12065 -0.305054)
			(stroke
				(width 0.1)
				(type default)
			)
			(layer "B.Fab")
		)
		(fp_line
			(start 0.67945 0.3048)
			(end 0.67945 -0.305054)
			(stroke
				(width 0.1)
				(type default)
			)
			(layer "B.Fab")
		)
		(pad "1" smd circle
			(at 0.40005 0 180)
			(size 0 0)
			(layers "B.Cu" "B.Mask" "B.Paste")
			(net "P1V2_AUX")
		)
		(pad "2" smd circle
			(at -0.40005 0 180)
			(size 0 0)
			(layers "B.Cu" "B.Mask" "B.Paste")
			(net "P1V2_AUX_ADC")
		)
	)
	(footprint ""
		(layer "B.Cu")
		(at 183.557164 -23.655782 -90)
		(property "Reference" "R3240"
			(at 0 0 90)
			(layer "B.SilkS")
			(hide yes)
			(effects
				(font
					(size 1.27 1.27)
				)
				(justify mirror)
			)
		)
		(property "Value" ""
			(at 0 0 90)
			(layer "B.Fab")
			(effects
				(font
					(size 1.27 1.27)
				)
				(justify mirror)
			)
		)
		(duplicate_pad_numbers_are_jumpers no)
		(fp_line
			(start -0.7874 0.4064)
			(end 0.7874 0.4064)
			(stroke
				(width 0.1524)
				(type default)
			)
			(layer "B.SilkS")
		)
		(fp_line
			(start 0.7874 0.4064)
			(end 0.7874 -0.4064)
			(stroke
				(width 0.1524)
				(type default)
			)
			(layer "B.SilkS")
		)
		(fp_line
			(start -0.7874 -0.4064)
			(end -0.7874 0.4064)
			(stroke
				(width 0.1524)
				(type default)
			)
			(layer "B.SilkS")
		)
		(fp_line
			(start 0.7874 -0.4064)
			(end -0.7874 -0.4064)
			(stroke
				(width 0.1524)
				(type default)
			)
			(layer "B.SilkS")
		)
		(fp_line
			(start -0.67945 0.3048)
			(end -0.120396 0.3048)
			(stroke
				(width 0.1)
				(type default)
			)
			(layer "B.Fab")
		)
		(fp_line
			(start -0.120396 0.3048)
			(end -0.120396 0.2794)
			(stroke
				(width 0.1)
				(type default)
			)
			(layer "B.Fab")
		)
		(fp_line
			(start 0.12065 0.3048)
			(end 0.67945 0.3048)
			(stroke
				(width 0.1)
				(type default)
			)
			(layer "B.Fab")
		)
		(fp_line
			(start 0.67945 0.3048)
			(end 0.67945 -0.305054)
			(stroke
				(width 0.1)
				(type default)
			)
			(layer "B.Fab")
		)
		(fp_line
			(start -0.120396 0.2794)
			(end 0.12065 0.2794)
			(stroke
				(width 0.1)
				(type default)
			)
			(layer "B.Fab")
		)
		(fp_line
			(start 0.12065 0.2794)
			(end 0.12065 0.3048)
			(stroke
				(width 0.1)
				(type default)
			)
			(layer "B.Fab")
		)
		(fp_line
			(start -0.12065 -0.2794)
			(end -0.12065 -0.3048)
			(stroke
				(width 0.1)
				(type default)
			)
			(layer "B.Fab")
		)
		(fp_line
			(start 0.12065 -0.2794)
			(end -0.12065 -0.2794)
			(stroke
				(width 0.1)
				(type default)
			)
			(layer "B.Fab")
		)
		(fp_line
			(start -0.67945 -0.3048)
			(end -0.67945 0.3048)
			(stroke
				(width 0.1)
				(type default)
			)
			(layer "B.Fab")
		)
		(fp_line
			(start -0.12065 -0.3048)
			(end -0.67945 -0.3048)
			(stroke
				(width 0.1)
				(type default)
			)
			(layer "B.Fab")
		)
		(fp_line
			(start 0.12065 -0.305054)
			(end 0.12065 -0.2794)
			(stroke
				(width 0.1)
				(type default)
			)
			(layer "B.Fab")
		)
		(fp_line
			(start 0.67945 -0.305054)
			(end 0.12065 -0.305054)
			(stroke
				(width 0.1)
				(type default)
			)
			(layer "B.Fab")
		)
		(pad "1" smd circle
			(at 0.40005 0 90)
			(size 0 0)
			(layers "B.Cu" "B.Mask" "B.Paste")
			(net "SMB_OCP_SFF_3V3AUX_SCL")
		)
		(pad "2" smd circle
			(at -0.40005 0 90)
			(size 0 0)
			(layers "B.Cu" "B.Mask" "B.Paste")
			(net "P3V3_AUX")
		)
	)
	(footprint ""
		(layer "B.Cu")
		(at 439.100214 -192.660016)
		(property "Reference" "C166"
			(at 0 0 0)
			(layer "B.SilkS")
			(hide yes)
			(effects
				(font
					(size 1.27 1.27)
				)
				(justify mirror)
			)
		)
		(property "Value" ""
			(at 0 0 0)
			(layer "B.Fab")
			(effects
				(font
					(size 1.27 1.27)
				)
				(justify mirror)
			)
		)
		(duplicate_pad_numbers_are_jumpers no)
		(fp_line
			(start -1.524 -0.762)
			(end -1.524 0.762)
			(stroke
				(width 0.1524)
				(type default)
			)
			(layer "B.SilkS")
		)
		(fp_line
			(start -1.524 0.762)
			(end 1.524 0.762)
			(stroke
				(width 0.1524)
				(type default)
			)
			(layer "B.SilkS")
		)
		(fp_line
			(start 1.524 -0.762)
			(end -1.524 -0.762)
			(stroke
				(width 0.1524)
				(type default)
			)
			(layer "B.SilkS")
		)
		(fp_line
			(start 1.524 0.762)
			(end 1.524 -0.762)
			(stroke
				(width 0.1524)
				(type default)
			)
			(layer "B.SilkS")
		)
		(fp_line
			(start -1.1049 -0.724916)
			(end 1.1049 -0.724916)
			(stroke
				(width 0.1)
				(type default)
			)
			(layer "B.Fab")
		)
		(fp_line
			(start -1.1049 0.724916)
			(end -1.1049 -0.724916)
			(stroke
				(width 0.1)
				(type default)
			)
			(layer "B.Fab")
		)
		(fp_line
			(start 1.1049 -0.724916)
			(end 1.1049 0.724916)
			(stroke
				(width 0.1)
				(type default)
			)
			(layer "B.Fab")
		)
		(fp_line
			(start 1.1049 0.724916)
			(end -1.1049 0.724916)
			(stroke
				(width 0.1)
				(type default)
			)
			(layer "B.Fab")
		)
		(pad "1" smd rect
			(at 0.889 0)
			(size 1.016 1.27)
			(layers "B.Cu" "B.Mask" "B.Paste")
			(net "P12V_MEM_CPU0")
		)
		(pad "2" smd rect
			(at -0.889 0)
			(size 1.016 1.27)
			(layers "B.Cu" "B.Mask" "B.Paste")
			(net "GND")
		)
	)
)
